(kicad_pcb
	(version 20260206)
	(generator "pcbnew")
	(generator_version "10.0")
	(general
		(thickness 1.6)
		(legacy_teardrops no)
	)
	(paper "A4")
	(title_block
		(title "baseboard — 13948-1b.1110WZS1818.brd")
		(comment 1 "Honey Badger (Wiwynn) / footprints 182-189 of 2523")
	)
	(layers
		(0 "F.Cu" signal "TOP")
		(4 "In1.Cu" signal "L2GND")
		(6 "In2.Cu" signal "L3")
		(8 "In3.Cu" signal "L4VCC")
		(10 "In4.Cu" signal "L5VCC")
		(12 "In5.Cu" signal "L6")
		(14 "In6.Cu" signal "L7GND")
		(2 "B.Cu" signal "BOTTOM")
		(9 "F.Adhes" user "F.Adhesive")
		(11 "B.Adhes" user "B.Adhesive")
		(13 "F.Paste" user "Package Geometry/Pastemask Top")
		(15 "B.Paste" user "Package Geometry/Pastemask Bottom")
		(5 "F.SilkS" user "Ref Des/Silkscreen Top")
		(7 "B.SilkS" user "Ref Des/Silkscreen Bottom")
		(1 "F.Mask" user "Board Geometry/Soldermask Top")
		(3 "B.Mask" user "Board Geometry/Soldermask Bottom")
		(17 "Dwgs.User" user "User.Drawings")
		(19 "Cmts.User" user "User.Comments")
		(21 "Eco1.User" user "User.Eco1")
		(23 "Eco2.User" user "User.Eco2")
		(25 "Edge.Cuts" user "Board Geometry/Outline")
		(27 "Margin" user)
		(31 "F.CrtYd" user "Package Geometry/Place Bound Top")
		(29 "B.CrtYd" user "Package Geometry/Place Bound Bottom")
		(35 "F.Fab" user "Ref Des/Assembly Top")
		(33 "B.Fab" user "Ref Des/Assembly Bottom")
	)
	(footprint ""
		(layer "F.Cu")
		(at 331.161136 -200.033128)
		(property "Reference" "R197"
			(at 0 0 0)
			(layer "F.SilkS")
			(hide yes)
			(effects
				(font
					(size 1.27 1.27)
				)
			)
		)
		(property "Value" "8K2R2J-3-GP"
			(at 0.064008 -3.993896 0)
			(unlocked yes)
			(layer "F.Fab")
			(hide yes)
			(effects
				(font
					(size 1.016 1.016)
					(thickness 0.1524)
				)
			)
		)
		(property "Device Type" "R402H16"
			(at 0.064008 -5.517896 0)
			(unlocked yes)
			(layer "F.Fab")
			(hide yes)
			(effects
				(font
					(size 1.016 1.016)
					(thickness 0.1524)
				)
			)
		)
		(duplicate_pad_numbers_are_jumpers no)
		(fp_line
			(start -0.508 -0.9398)
			(end -0.508 0.9398)
			(stroke
				(width 0.1524)
				(type default)
			)
			(layer "F.SilkS")
		)
		(fp_line
			(start 0.508 -0.9398)
			(end -0.508 -0.9398)
			(stroke
				(width 0.1524)
				(type default)
			)
			(layer "F.SilkS")
		)
		(fp_rect
			(start -0.508 0.9398)
			(end 0.508 -0.9398)
			(stroke
				(width 0)
				(type default)
			)
			(fill no)
			(layer "F.CrtYd")
		)
		(fp_rect
			(start -0.508 0.9398)
			(end 0.508 -0.9398)
			(stroke
				(width 0)
				(type default)
			)
			(fill no)
			(layer "F.Fab")
		)
		(pad "1" smd custom
			(at 0 -0.4445)
			(size 0.1397 0.1397)
			(layers "F.Cu" "F.Mask" "F.Paste")
			(net "EEPROM_A0_R")
			(options
				(clearance outline)
				(anchor circle)
			)
			(primitives
				(gr_poly
					(pts
						(arc
							(start -0.1778 -0.2794)
							(mid -0.249642 -0.249642)
							(end -0.2794 -0.1778)
						)
						(arc
							(start -0.2794 0.1778)
							(mid -0.249642 0.249642)
							(end -0.1778 0.2794)
						)
						(arc
							(start 0.1778 0.2794)
							(mid 0.249642 0.249642)
							(end 0.2794 0.1778)
						)
						(arc
							(start 0.2794 -0.1778)
							(mid 0.249642 -0.249642)
							(end 0.1778 -0.2794)
						)
					)
					(width 0)
					(fill yes)
				)
			)
		)
		(pad "2" smd custom
			(at 0 0.4445)
			(size 0.1397 0.1397)
			(layers "F.Cu" "F.Mask" "F.Paste")
			(net "GND")
			(options
				(clearance outline)
				(anchor circle)
			)
			(primitives
				(gr_poly
					(pts
						(arc
							(start -0.1778 -0.2794)
							(mid -0.249642 -0.249642)
							(end -0.2794 -0.1778)
						)
						(arc
							(start -0.2794 0.1778)
							(mid -0.249642 0.249642)
							(end -0.1778 0.2794)
						)
						(arc
							(start 0.1778 0.2794)
							(mid 0.249642 0.249642)
							(end 0.2794 0.1778)
						)
						(arc
							(start 0.2794 -0.1778)
							(mid 0.249642 -0.249642)
							(end 0.1778 -0.2794)
						)
					)
					(width 0)
					(fill yes)
				)
			)
		)
	)
	(footprint ""
		(layer "F.Cu")
		(at 120.847612 -204.978)
		(property "Reference" "SR868"
			(at 0 0 0)
			(layer "F.SilkS")
			(hide yes)
			(effects
				(font
					(size 1.27 1.27)
				)
			)
		)
		(property "Value" "0R2J-2-GP"
			(at 0.064008 -3.993896 0)
			(unlocked yes)
			(layer "F.Fab")
			(hide yes)
			(effects
				(font
					(size 1.016 1.016)
					(thickness 0.1524)
				)
			)
		)
		(property "Device Type" "R402H16"
			(at 0.064008 -5.517896 0)
			(unlocked yes)
			(layer "F.Fab")
			(hide yes)
			(effects
				(font
					(size 1.016 1.016)
					(thickness 0.1524)
				)
			)
		)
		(duplicate_pad_numbers_are_jumpers no)
		(fp_line
			(start -0.508 -0.9398)
			(end -0.508 0.9398)
			(stroke
				(width 0.1524)
				(type default)
			)
			(layer "F.SilkS")
		)
		(fp_line
			(start 0.508 -0.9398)
			(end -0.508 -0.9398)
			(stroke
				(width 0.1524)
				(type default)
			)
			(layer "F.SilkS")
		)
		(fp_rect
			(start -0.508 0.9398)
			(end 0.508 -0.9398)
			(stroke
				(width 0)
				(type default)
			)
			(fill no)
			(layer "F.CrtYd")
		)
		(fp_rect
			(start -0.508 0.9398)
			(end 0.508 -0.9398)
			(stroke
				(width 0)
				(type default)
			)
			(fill no)
			(layer "F.Fab")
		)
		(pad "1" smd custom
			(at 0 -0.4445)
			(size 0.1397 0.1397)
			(layers "F.Cu" "F.Mask" "F.Paste")
			(net "SAS_HDD_REDV_TX7_P")
			(options
				(clearance outline)
				(anchor circle)
			)
			(primitives
				(gr_poly
					(pts
						(arc
							(start -0.1778 -0.2794)
							(mid -0.249642 -0.249642)
							(end -0.2794 -0.1778)
						)
						(arc
							(start -0.2794 0.1778)
							(mid -0.249642 0.249642)
							(end -0.1778 0.2794)
						)
						(arc
							(start 0.1778 0.2794)
							(mid 0.249642 0.249642)
							(end 0.2794 0.1778)
						)
						(arc
							(start 0.2794 -0.1778)
							(mid 0.249642 -0.249642)
							(end 0.1778 -0.2794)
						)
					)
					(width 0)
					(fill yes)
				)
			)
		)
		(pad "2" smd custom
			(at 0 0.4445)
			(size 0.1397 0.1397)
			(layers "F.Cu" "F.Mask" "F.Paste")
			(net "SAS_HDD_REDV_SER_TX7_P")
			(options
				(clearance outline)
				(anchor circle)
			)
			(primitives
				(gr_poly
					(pts
						(arc
							(start -0.1778 -0.2794)
							(mid -0.249642 -0.249642)
							(end -0.2794 -0.1778)
						)
						(arc
							(start -0.2794 0.1778)
							(mid -0.249642 0.249642)
							(end -0.1778 0.2794)
						)
						(arc
							(start 0.1778 0.2794)
							(mid 0.249642 0.249642)
							(end 0.2794 0.1778)
						)
						(arc
							(start 0.2794 -0.1778)
							(mid 0.249642 -0.249642)
							(end 0.1778 -0.2794)
						)
					)
					(width 0)
					(fill yes)
				)
			)
		)
	)
	(footprint ""
		(layer "F.Cu")
		(at 288.798 -160.782 180)
		(property "Reference" "R530"
			(at 0 0 180)
			(layer "F.SilkS")
			(hide yes)
			(effects
				(font
					(size 1.27 1.27)
				)
			)
		)
		(property "Value" "0R2J-2-GP"
			(at 0.064008 -3.993896 180)
			(unlocked yes)
			(layer "F.Fab")
			(hide yes)
			(effects
				(font
					(size 1.016 1.016)
					(thickness 0.1524)
				)
			)
		)
		(property "Device Type" "R402H16"
			(at 0.064008 -5.517896 180)
			(unlocked yes)
			(layer "F.Fab")
			(hide yes)
			(effects
				(font
					(size 1.016 1.016)
					(thickness 0.1524)
				)
			)
		)
		(duplicate_pad_numbers_are_jumpers no)
		(fp_line
			(start 0.508 -0.9398)
			(end -0.508 -0.9398)
			(stroke
				(width 0.1524)
				(type default)
			)
			(layer "F.SilkS")
		)
		(fp_line
			(start -0.508 -0.9398)
			(end -0.508 0.9398)
			(stroke
				(width 0.1524)
				(type default)
			)
			(layer "F.SilkS")
		)
		(fp_rect
			(start -0.508 0.9398)
			(end 0.508 -0.9398)
			(stroke
				(width 0)
				(type default)
			)
			(fill no)
			(layer "F.CrtYd")
		)
		(fp_rect
			(start -0.508 0.9398)
			(end 0.508 -0.9398)
			(stroke
				(width 0)
				(type default)
			)
			(fill no)
			(layer "F.Fab")
		)
		(pad "1" smd custom
			(at 0 -0.4445 180)
			(size 0.1397 0.1397)
			(layers "F.Cu" "F.Mask" "F.Paste")
			(net "FM_BMC_READY_N")
			(options
				(clearance outline)
				(anchor circle)
			)
			(primitives
				(gr_poly
					(pts
						(arc
							(start -0.1778 -0.2794)
							(mid -0.249642 -0.249642)
							(end -0.2794 -0.1778)
						)
						(arc
							(start -0.2794 0.1778)
							(mid -0.249642 0.249642)
							(end -0.1778 0.2794)
						)
						(arc
							(start 0.1778 0.2794)
							(mid 0.249642 0.249642)
							(end 0.2794 0.1778)
						)
						(arc
							(start 0.2794 -0.1778)
							(mid 0.249642 -0.249642)
							(end 0.1778 -0.2794)
						)
					)
					(width 0)
					(fill yes)
				)
			)
		)
		(pad "2" smd custom
			(at 0 0.4445 180)
			(size 0.1397 0.1397)
			(layers "F.Cu" "F.Mask" "F.Paste")
			(net "FM_BMC_READY_N_R")
			(options
				(clearance outline)
				(anchor circle)
			)
			(primitives
				(gr_poly
					(pts
						(arc
							(start -0.1778 -0.2794)
							(mid -0.249642 -0.249642)
							(end -0.2794 -0.1778)
						)
						(arc
							(start -0.2794 0.1778)
							(mid -0.249642 0.249642)
							(end -0.1778 0.2794)
						)
						(arc
							(start 0.1778 0.2794)
							(mid 0.249642 0.249642)
							(end 0.2794 0.1778)
						)
						(arc
							(start 0.2794 -0.1778)
							(mid 0.249642 -0.249642)
							(end 0.1778 -0.2794)
						)
					)
					(width 0)
					(fill yes)
				)
			)
		)
	)
	(footprint ""
		(layer "F.Cu")
		(at 85.452966 -91.44 180)
		(property "Reference" "SC1199"
			(at 0 0 180)
			(layer "F.SilkS")
			(hide yes)
			(effects
				(font
					(size 1.27 1.27)
				)
			)
		)
		(property "Value" "SC10U6D3V5KX-4GP"
			(at -0.0762 -6.1214 180)
			(unlocked yes)
			(layer "F.Fab")
			(hide yes)
			(effects
				(font
					(size 1.016 1.016)
					(thickness 0.1524)
				)
			)
		)
		(property "Device Type" "C805H58"
			(at -0.0762 -8.1534 180)
			(unlocked yes)
			(layer "F.Fab")
			(hide yes)
			(effects
				(font
					(size 1.016 1.016)
					(thickness 0.1524)
				)
			)
		)
		(duplicate_pad_numbers_are_jumpers no)
		(fp_line
			(start 0.635 0)
			(end -0.635 0)
			(stroke
				(width 0.508)
				(type default)
			)
			(layer "F.SilkS")
		)
		(fp_rect
			(start -0.9652 1.778)
			(end 0.9652 -1.778)
			(stroke
				(width 0)
				(type default)
			)
			(fill no)
			(layer "F.CrtYd")
		)
		(fp_poly
			(pts
				(xy -0.9652 -1.778) (xy 0.9652 -1.778) (xy 0.9652 1.778) (xy -0.9652 1.778)
			)
			(stroke
				(width 0)
				(type default)
			)
			(fill no)
			(layer "F.Fab")
		)
		(pad "1" smd rect
			(at 0 -0.9652 180)
			(size 1.397 1.143)
			(layers "F.Cu" "F.Mask" "F.Paste")
			(net "SYSPLL_VDDA09")
		)
		(pad "2" smd rect
			(at 0 0.9652 180)
			(size 1.397 1.143)
			(layers "F.Cu" "F.Mask" "F.Paste")
			(net "GND")
		)
	)
	(footprint ""
		(layer "F.Cu")
		(at 35.383216 -201.09688 -90)
		(property "Reference" "R565"
			(at 0 0 270)
			(layer "F.SilkS")
			(hide yes)
			(effects
				(font
					(size 1.27 1.27)
				)
			)
		)
		(property "Value" "0R2J-2-GP"
			(at 0.064008 -3.993896 270)
			(unlocked yes)
			(layer "F.Fab")
			(hide yes)
			(effects
				(font
					(size 1.016 1.016)
					(thickness 0.1524)
				)
			)
		)
		(property "Device Type" "R402H16"
			(at 0.064008 -5.517896 270)
			(unlocked yes)
			(layer "F.Fab")
			(hide yes)
			(effects
				(font
					(size 1.016 1.016)
					(thickness 0.1524)
				)
			)
		)
		(duplicate_pad_numbers_are_jumpers no)
		(fp_line
			(start -0.508 -0.9398)
			(end -0.508 0.9398)
			(stroke
				(width 0.1524)
				(type default)
			)
			(layer "F.SilkS")
		)
		(fp_line
			(start 0.508 -0.9398)
			(end -0.508 -0.9398)
			(stroke
				(width 0.1524)
				(type default)
			)
			(layer "F.SilkS")
		)
		(fp_rect
			(start -0.508 0.9398)
			(end 0.508 -0.9398)
			(stroke
				(width 0)
				(type default)
			)
			(fill no)
			(layer "F.CrtYd")
		)
		(fp_rect
			(start -0.508 0.9398)
			(end 0.508 -0.9398)
			(stroke
				(width 0)
				(type default)
			)
			(fill no)
			(layer "F.Fab")
		)
		(pad "1" smd custom
			(at 0 -0.4445 270)
			(size 0.1397 0.1397)
			(layers "F.Cu" "F.Mask" "F.Paste")
			(net "ADC_P1V5_C")
			(options
				(clearance outline)
				(anchor circle)
			)
			(primitives
				(gr_poly
					(pts
						(arc
							(start -0.1778 -0.2794)
							(mid -0.249642 -0.249642)
							(end -0.2794 -0.1778)
						)
						(arc
							(start -0.2794 0.1778)
							(mid -0.249642 0.249642)
							(end -0.1778 0.2794)
						)
						(arc
							(start 0.1778 0.2794)
							(mid 0.249642 0.249642)
							(end 0.2794 0.1778)
						)
						(arc
							(start 0.2794 -0.1778)
							(mid 0.249642 -0.249642)
							(end 0.1778 -0.2794)
						)
					)
					(width 0)
					(fill yes)
				)
			)
		)
		(pad "2" smd custom
			(at 0 0.4445 270)
			(size 0.1397 0.1397)
			(layers "F.Cu" "F.Mask" "F.Paste")
			(net "P1V5_C_SENSE")
			(options
				(clearance outline)
				(anchor circle)
			)
			(primitives
				(gr_poly
					(pts
						(arc
							(start -0.1778 -0.2794)
							(mid -0.249642 -0.249642)
							(end -0.2794 -0.1778)
						)
						(arc
							(start -0.2794 0.1778)
							(mid -0.249642 0.249642)
							(end -0.1778 0.2794)
						)
						(arc
							(start 0.1778 0.2794)
							(mid 0.249642 0.249642)
							(end 0.2794 0.1778)
						)
						(arc
							(start 0.2794 -0.1778)
							(mid 0.249642 -0.249642)
							(end 0.1778 -0.2794)
						)
					)
					(width 0)
					(fill yes)
				)
			)
		)
	)
	(footprint ""
		(layer "F.Cu")
		(at 223.647 -121.158 180)
		(property "Reference" "R606"
			(at 0 0 180)
			(layer "F.SilkS")
			(hide yes)
			(effects
				(font
					(size 1.27 1.27)
				)
			)
		)
		(property "Value" "4K7R2F-GP"
			(at 0.064008 -3.993896 180)
			(unlocked yes)
			(layer "F.Fab")
			(hide yes)
			(effects
				(font
					(size 1.016 1.016)
					(thickness 0.1524)
				)
			)
		)
		(property "Device Type" "R402H16"
			(at 0.064008 -5.517896 180)
			(unlocked yes)
			(layer "F.Fab")
			(hide yes)
			(effects
				(font
					(size 1.016 1.016)
					(thickness 0.1524)
				)
			)
		)
		(duplicate_pad_numbers_are_jumpers no)
		(fp_line
			(start 0.508 -0.9398)
			(end -0.508 -0.9398)
			(stroke
				(width 0.1524)
				(type default)
			)
			(layer "F.SilkS")
		)
		(fp_line
			(start -0.508 -0.9398)
			(end -0.508 0.9398)
			(stroke
				(width 0.1524)
				(type default)
			)
			(layer "F.SilkS")
		)
		(fp_rect
			(start -0.508 0.9398)
			(end 0.508 -0.9398)
			(stroke
				(width 0)
				(type default)
			)
			(fill no)
			(layer "F.CrtYd")
		)
		(fp_rect
			(start -0.508 0.9398)
			(end 0.508 -0.9398)
			(stroke
				(width 0)
				(type default)
			)
			(fill no)
			(layer "F.Fab")
		)
		(pad "1" smd custom
			(at 0 -0.4445 180)
			(size 0.1397 0.1397)
			(layers "F.Cu" "F.Mask" "F.Paste")
			(net "P1V8_C_B")
			(options
				(clearance outline)
				(anchor circle)
			)
			(primitives
				(gr_poly
					(pts
						(arc
							(start -0.1778 -0.2794)
							(mid -0.249642 -0.249642)
							(end -0.2794 -0.1778)
						)
						(arc
							(start -0.2794 0.1778)
							(mid -0.249642 0.249642)
							(end -0.1778 0.2794)
						)
						(arc
							(start 0.1778 0.2794)
							(mid 0.249642 0.249642)
							(end 0.2794 0.1778)
						)
						(arc
							(start 0.2794 -0.1778)
							(mid 0.249642 -0.249642)
							(end 0.1778 -0.2794)
						)
					)
					(width 0)
					(fill yes)
				)
			)
		)
		(pad "2" smd custom
			(at 0 0.4445 180)
			(size 0.1397 0.1397)
			(layers "F.Cu" "F.Mask" "F.Paste")
			(net "P1V8_C")
			(options
				(clearance outline)
				(anchor circle)
			)
			(primitives
				(gr_poly
					(pts
						(arc
							(start -0.1778 -0.2794)
							(mid -0.249642 -0.249642)
							(end -0.2794 -0.1778)
						)
						(arc
							(start -0.2794 0.1778)
							(mid -0.249642 0.249642)
							(end -0.1778 0.2794)
						)
						(arc
							(start 0.1778 0.2794)
							(mid 0.249642 0.249642)
							(end 0.2794 0.1778)
						)
						(arc
							(start 0.2794 -0.1778)
							(mid 0.249642 -0.249642)
							(end 0.1778 -0.2794)
						)
					)
					(width 0)
					(fill yes)
				)
			)
		)
	)
	(footprint ""
		(layer "F.Cu")
		(at 49.9872 -231.01554)
		(property "Reference" "C296"
			(at 0 0 0)
			(layer "F.SilkS")
			(hide yes)
			(effects
				(font
					(size 1.27 1.27)
				)
			)
		)
		(property "Value" "SC22U25V5MX-GP"
			(at -0.0762 -6.1214 0)
			(unlocked yes)
			(layer "F.Fab")
			(hide yes)
			(effects
				(font
					(size 1.016 1.016)
					(thickness 0.1524)
				)
			)
		)
		(property "Device Type" "C805H58"
			(at -0.0762 -8.1534 0)
			(unlocked yes)
			(layer "F.Fab")
			(hide yes)
			(effects
				(font
					(size 1.016 1.016)
					(thickness 0.1524)
				)
			)
		)
		(duplicate_pad_numbers_are_jumpers no)
		(fp_line
			(start 0.635 0)
			(end -0.635 0)
			(stroke
				(width 0.508)
				(type default)
			)
			(layer "F.SilkS")
		)
		(fp_rect
			(start -0.9652 1.778)
			(end 0.9652 -1.778)
			(stroke
				(width 0)
				(type default)
			)
			(fill no)
			(layer "F.CrtYd")
		)
		(fp_poly
			(pts
				(xy -0.9652 -1.778) (xy 0.9652 -1.778) (xy 0.9652 1.778) (xy -0.9652 1.778)
			)
			(stroke
				(width 0)
				(type default)
			)
			(fill no)
			(layer "F.Fab")
		)
		(pad "1" smd rect
			(at 0 -0.9652)
			(size 1.397 1.143)
			(layers "F.Cu" "F.Mask" "F.Paste")
			(net "P12V_PCIE")
		)
		(pad "2" smd rect
			(at 0 0.9652)
			(size 1.397 1.143)
			(layers "F.Cu" "F.Mask" "F.Paste")
			(net "GND")
		)
	)
	(footprint ""
		(layer "F.Cu")
		(at 276.850094 -25.791668)
		(property "Reference" "R410"
			(at 0 0 0)
			(layer "F.SilkS")
			(hide yes)
			(effects
				(font
					(size 1.27 1.27)
				)
			)
		)
		(property "Value" "0R2J-2-GP"
			(at 0.064008 -3.993896 0)
			(unlocked yes)
			(layer "F.Fab")
			(hide yes)
			(effects
				(font
					(size 1.016 1.016)
					(thickness 0.1524)
				)
			)
		)
		(property "Device Type" "R402H16"
			(at 0.064008 -5.517896 0)
			(unlocked yes)
			(layer "F.Fab")
			(hide yes)
			(effects
				(font
					(size 1.016 1.016)
					(thickness 0.1524)
				)
			)
		)
		(duplicate_pad_numbers_are_jumpers no)
		(fp_line
			(start -0.508 -0.9398)
			(end -0.508 0.9398)
			(stroke
				(width 0.1524)
				(type default)
			)
			(layer "F.SilkS")
		)
		(fp_line
			(start 0.508 -0.9398)
			(end -0.508 -0.9398)
			(stroke
				(width 0.1524)
				(type default)
			)
			(layer "F.SilkS")
		)
		(fp_rect
			(start -0.508 0.9398)
			(end 0.508 -0.9398)
			(stroke
				(width 0)
				(type default)
			)
			(fill no)
			(layer "F.CrtYd")
		)
		(fp_rect
			(start -0.508 0.9398)
			(end 0.508 -0.9398)
			(stroke
				(width 0)
				(type default)
			)
			(fill no)
			(layer "F.Fab")
		)
		(pad "1" smd custom
			(at 0 -0.4445)
			(size 0.1397 0.1397)
			(layers "F.Cu" "F.Mask" "F.Paste")
			(net "USB_DN_R")
			(options
				(clearance outline)
				(anchor circle)
			)
			(primitives
				(gr_poly
					(pts
						(arc
							(start -0.1778 -0.2794)
							(mid -0.249642 -0.249642)
							(end -0.2794 -0.1778)
						)
						(arc
							(start -0.2794 0.1778)
							(mid -0.249642 0.249642)
							(end -0.1778 0.2794)
						)
						(arc
							(start 0.1778 0.2794)
							(mid 0.249642 0.249642)
							(end 0.2794 0.1778)
						)
						(arc
							(start 0.2794 -0.1778)
							(mid 0.249642 -0.249642)
							(end 0.1778 -0.2794)
						)
					)
					(width 0)
					(fill yes)
				)
			)
		)
		(pad "2" smd custom
			(at 0 0.4445)
			(size 0.1397 0.1397)
			(layers "F.Cu" "F.Mask" "F.Paste")
			(net "USB_P1_F_DN1")
			(options
				(clearance outline)
				(anchor circle)
			)
			(primitives
				(gr_poly
					(pts
						(arc
							(start -0.1778 -0.2794)
							(mid -0.249642 -0.249642)
							(end -0.2794 -0.1778)
						)
						(arc
							(start -0.2794 0.1778)
							(mid -0.249642 0.249642)
							(end -0.1778 0.2794)
						)
						(arc
							(start 0.1778 0.2794)
							(mid 0.249642 0.249642)
							(end 0.2794 0.1778)
						)
						(arc
							(start 0.2794 -0.1778)
							(mid 0.249642 -0.249642)
							(end 0.1778 -0.2794)
						)
					)
					(width 0)
					(fill yes)
				)
			)
		)
	)
)
